# T6G (Grand Teton) — schematic netlist excerpt (pin names and nets, part order shuffled) for the footprints in the layout excerpt that follows; sources: Cadence DE-HDL packaged netlist, KiCad conversion of 04192023_DAF0TMB3IC0_F0TG_MB_C_brd_V02_OCP.brd

R796  Q_RES  1K 1% CHIP  pkg 0201LF  page 331 : A = RT_CPU1_P1_ADDR1 ; B = GND

(kicad_pcb
	(version 20260206)
	(generator "pcbnew")
	(generator_version "10.0")
	(general
		(thickness 1.6)
		(legacy_teardrops no)
	)
	(paper "A4")
	(title_block
		(title "04192023_DAF0TMB3IC0_F0TG_MB_C_brd_V02_OCP.brd")
		(comment 1 "Grand Teton / footprints 3954-3954 of 8354")
	)
	(layers
		(0 "F.Cu" signal "TOP")
		(4 "In1.Cu" signal "GND")
		(6 "In2.Cu" signal "IN1")
		(8 "In3.Cu" signal "GND1")
		(10 "In4.Cu" signal "IN2")
		(12 "In5.Cu" signal "GND2")
		(14 "In6.Cu" signal "IN3")
		(16 "In7.Cu" signal "GND3")
		(18 "In8.Cu" signal "VCC")
		(20 "In9.Cu" signal "VCC1")
		(22 "In10.Cu" signal "GND4")
		(24 "In11.Cu" signal "IN4")
		(26 "In12.Cu" signal "GND5")
		(28 "In13.Cu" signal "IN5")
		(30 "In14.Cu" signal "GND6")
		(32 "In15.Cu" signal "IN6")
		(34 "In16.Cu" signal "GND7")
		(2 "B.Cu" signal "BOTTOM")
		(9 "F.Adhes" user "F.Adhesive")
		(11 "B.Adhes" user "B.Adhesive")
		(13 "F.Paste" user "Package Geometry/Pastemask Top")
		(15 "B.Paste" user "Package Geometry/Pastemask Bottom")
		(5 "F.SilkS" user "Ref Des/Silkscreen Top")
		(7 "B.SilkS" user "Ref Des/Silkscreen Bottom")
		(1 "F.Mask" user "Board Geometry/Soldermask Top")
		(3 "B.Mask" user "Board Geometry/Soldermask Bottom")
		(17 "Dwgs.User" user "User.Drawings")
		(19 "Cmts.User" user "User.Comments")
		(21 "Eco1.User" user "User.Eco1")
		(23 "Eco2.User" user "User.Eco2")
		(25 "Edge.Cuts" user "Board Geometry/Outline")
		(27 "Margin" user)
		(31 "F.CrtYd" user "Package Geometry/Place Bound Top")
		(29 "B.CrtYd" user "Package Geometry/Place Bound Bottom")
		(35 "F.Fab" user "Ref Des/Assembly Top")
		(33 "B.Fab" user "Ref Des/Assembly Bottom")
	)
	(footprint ""
		(layer "F.Cu")
		(at 104.816148 -382.27)
		(property "Reference" "R796"
			(at 0 0 0)
			(layer "F.SilkS")
			(hide yes)
			(effects
				(font
					(size 1.27 1.27)
				)
			)
		)
		(property "Value" ""
			(at 0 0 0)
			(layer "F.Fab")
			(effects
				(font
					(size 1.27 1.27)
				)
			)
		)
		(duplicate_pad_numbers_are_jumpers no)
		(fp_line
			(start -0.32512 -0.175006)
			(end 0.32512 -0.175006)
			(stroke
				(width 0.1)
				(type default)
			)
			(layer "F.Fab")
		)
		(fp_line
			(start -0.32512 0.175006)
			(end -0.32512 -0.175006)
			(stroke
				(width 0.1)
				(type default)
			)
			(layer "F.Fab")
		)
		(fp_line
			(start 0.32512 -0.175006)
			(end 0.32512 0.175006)
			(stroke
				(width 0.1)
				(type default)
			)
			(layer "F.Fab")
		)
		(fp_line
			(start 0.32512 0.175006)
			(end -0.32512 0.175006)
			(stroke
				(width 0.1)
				(type default)
			)
			(layer "F.Fab")
		)
		(pad "1" smd rect
			(at -0.2667 0)
			(size 0.3048 0.381)
			(layers "F.Cu" "F.Mask" "F.Paste")
			(net "RT_CPU1_P1_ADDR1")
		)
		(pad "2" smd rect
			(at 0.2667 0 180)
			(size 0.3048 0.381)
			(layers "F.Cu" "F.Mask" "F.Paste")
			(net "GND")
		)
	)
)
